# BARRELEYE-G2-EXPANDER-EVT-HW-EBOM-X00-20161124-add_2nd_source_X06-20161207-Final.xls — DEPOP (bom)
| FOXCONN TECHNOLOGY GROUP |  |  |  |  |  |  |  |  |  |  |  |  |
| BILL OF MATERIAL |  |  |  |  |  |  |  |  |  |  |  |  |
| REV OF  BOM |  | CUSTOMER | <name> |  | CUSTOMER P/N |  | PRODUCT CODE |  | PWA  REV |  | DATE |  |
| Sourcing (Single/Sole/Multi) | Critical Commodity (Y or N) | Component Class (1, 2, other) | Customer PSL (Y or N) | Item Number | Foxconn P/N | Customer P/N | Part Description | Manufacturer  Full Name | Manufacturer  Part Number | Qty | RoHS Status | Location |
|  |  |  |  | 1 | 620101T02-015-G | - | CAP,100nF,+/-10%,X7R,16V,G,SMD0402 | MURATA ELEC. NORTH AMERICA | GRM155R71C104K | 3 |  | PSCC13,C232,C408 |
|  |  |  |  | 2 | 620100D00-015-G |  | CAP,100nF,+/-10%,X7R,16V,G,SMD0603 | MURATA ELEC. NORTH AMERICA | GRM188R71C104K | 2 |  | C401,C405 |
|  |  |  |  | 3 | 62012A400-015-G | - | CAP,100nF,+/-10%,X7R,25V,G,SMD0402 | MURATA ELEC. NORTH AMERICA | GRM155R71E104KE14D | 1 |  | C407 |
|  |  |  |  | 4 | 61010LA00-017-G | - | RES,4.7KOhm,+/-1%,1/16W,G,SMD0402 | KOA SPEER ELECTRONICS, INC. | RK73H1ETTP4701F | 4 |  | PSCR16,R253,R254,PSCR3005 |
|  |  |  |  | 5 | 610107A00-017-G | - | RES,0 Ohm,+/-5%,1/16W,G,SMD0402 | KOA SPEER ELECTRONICS, INC. | RK73Z1ETTP | 11 |  | PSRR8,PSLR8,PSGR8,PSGR13,PSCR17,R176,R231,R232,R235,R243,PSCR3014 |
|  |  |  |  | 6 | 61100J300-017-G |  | RES,121 Ohm,+/-0.1%,1/16W,G,SMD0402 | KOA SPEER ELECTRONICS, INC. | RN731ETTP1210B25 | 2 |  | PSCR18,PSCR3015 |
|  |  |  |  | 7 | 61100U300-017-G |  | RES,210 Ohm,+/-0.1%,1/16W,G,SMD0402 | KOA SPEER ELECTRONICS, INC. | RN731ETTP2100B25 | 1 |  | PSCR19 |
|  |  |  |  | 8 | 61012JH00-017-G |  | RES,470 Ohm,+/-5%,1/8W,G,SMD0805 | KOA SPEER ELECTRONICS, INC. | RK73B2ATTD471J | 4 |  | PSRR20,PSLR20,PSGR20,PSCR3000 |
|  |  |  |  | 9 | 61100BP00-017-G |  | RES,3.09KOhm,+/-0.1%,1/16W,G,SMD0402 | KOA SPEER ELECTRONICS, INC. | RN731ETTP3091B25 | 1 |  | PSCR3006 |
|  |  |  |  | 10 | 62010QB00-015-G | - | CAP,10nF,+/-10%,X7R,50V,G,SMD0402 | MURATA ELEC. NORTH AMERICA | GRM155R71H103K | 3 |  | PSRC9,PSLC9,PSGC9 |
|  |  |  |  | 11 | 620105U00-015-G | - | CAP,220pF,+/-10%,X7R,50V,G,SMD0402 | MURATA ELEC. NORTH AMERICA | GRM155R71H221K | 3 |  | PSRC13,PSLC13,PSGC13 |
|  |  |  |  | 12 | 610112M00-017-G |  | RES,13KOhm,+/-1%,1/16W,G,SMD0402 | KOA SPEER ELECTRONICS, INC. | RK73H1ETTP1302F | 2 |  | PSLR1,PSGR1 |
|  |  |  |  | 13 | 610114H00-017-G | - | RES,20KOhm,+/-1%,1/16W,G,SMD0402 | KOA SPEER ELECTRONICS, INC. | RK73H1ETTP2002F | 2 |  | PSLR3,PSGR3 |
|  |  |  |  | 14 | 61011HA00-017-G |  | RES,1 Ohm,+/-1%,1/16W,G,SMD0402 | KOA SPEER ELECTRONICS, INC. | RK73H1ETTP1R00F | 3 |  | PSRR14,PSLR14,PSGR14 |
|  |  |  |  | 15 | 61010JY00-017-G | - | RES,220 Ohm,+/-5%,1/16W,G,SMD0402 | KOA SPEER ELECTRONICS, INC. | RK73B1ETTP221J | 6 |  | R7,R140,R142,R191,R193,R199 |
|  |  |  |  | 16 | 610114J00-017-G | - | RES,2KOhm,+/-1%,1/16W,G,SMD0402 | KOA SPEER ELECTRONICS, INC. | RK73H1ETTP2001F | 7 |  | R19,R20,R21,R22,R23,R24,R25 |
|  |  |  |  | 17 | 610112W00-017-G |  | RES,2KOhm,+/-5%,1/16W,G,SMD0402 | KOA SPEER ELECTRONICS, INC. | RK73B1ETTP202J | 12 |  | R31,R32,R35,R37,R52,R56,R85,R88,R94,R100,R101,R138 |
|  |  |  |  | 18 | 61011MQ00-017-G | - | RES,4.75KOhm,+/-1%,1/16W,G,SMD0402 | KOA SPEER ELECTRONICS, INC. | RK73H1ETTP4751F | 10 |  | R33,R70,R71,R72,R86,R186,R187,R196,R197,R249 |
|  |  |  |  | 19 | 61010G500-017-G | - | RES,10KOhm,+/-1%,1/16W,G,SMD0402 | KOA SPEER ELECTRONICS, INC. | RK73H1ETTP1002F | 1 |  | R47 |
|  |  |  |  | 20 | 61010L100-017-G | - | RES,100KOhm,+/-1%,1/16W,G,SMD0402 | KOA SPEER ELECTRONICS, INC. | RK73H1ETTP1003F | 4 |  | R236,R239,R244,R246 |
|  |  |  |  | 21 | 420103G00-244-G | - | SRAM,CY14V101LA-BA45XIT,3.0~3.6V,1M,G,FBGA-48,SMD | CYPRESS SEMICONDUCTOR CORP | CY14V101LA-BA45XIT | 1 |  | U_EXP_NVSRAM2 |
|  |  |  |  | 22 | 310101400-031-G | - | IC,Gate&Inverter,74LVC1G08GW,1.65~5.5V,G,SOT353-5,SMD | NXP SEMICONDUCTORS | 74LVC1G08GW | 1 |  | U5 |
|  |  |  |  | 23 | 34062K700-742-G |  | CONN,Socket,2X28,V/T,0.5mm,G,SMD-56 | MERITEC | 980020-56-P1-K | 1 |  | J_FLASH_SOCKET1 |
|  |  |  |  | 24 | 62010L800-015-G | - | CAP,1nF,+/-5%,NPO(C0G),50V,G,SMD0402 | MURATA ELEC. NORTH AMERICA | GRM1555C1H102J | 1 |  | PSCC5 |
|  |  |  |  | 25 | 61011HA00-017-G |  | RES,1 Ohm,+/-1%,1/16W,G,SMD0402 | KOA SPEER ELECTRONICS, INC. | RK73H1ETTP1R00F | 1 |  | PSCR4 |
